# S9S_MB_2U (Grand Teton) — schematic netlist excerpt (pin names and nets, part order shuffled) for the footprints in the layout excerpt that follows; sources: Cadence DE-HDL packaged netlist, KiCad conversion of 03242023_DA0F0TMBIJ0_F0T_Motherboard_J_brd_V01_OCP.brd

J45  CONN60_101062636003K02LF  CONN60_10106263-6003K02LF IO  pkg HSD_M60D4H2D_P2-54W2-54_LDHXB  page 245
  A1  = TP_J45_A1
  A2  = FM_AC_PWR_BTN_PDB_N
  A3  = P3V3_PDB_AUX_ADC
  B1  = RST_SMB_SWITCH_R_N
  B2  = PWRGD_P3V3_AUX_PDB_BUF
  B3  = GND
  C1  = SMB_FAN_3V3AUX_BUF_R_SCL
  C2  = SMB_FAN_3V3AUX_BUF_R_SDA
  C3  = HPDB_HSC_PWRGD_R
  D1  = FM_FAN_PWR_EN_R
  D2  = FM_GPU_HSC_EN_BUF_R1
  D3  = PDB_PRSNT_N
  P1_1  = GND
  P1_2  = GND
  P1_3  = GND
  P1_4  = GND
  P1_5  = GND
  P1_6  = GND
  P1_7  = GND
  P1_8  = GND
  P2_1  = GND
  P2_2  = GND
  P2_3  = GND
  P2_4  = GND
  P2_5  = GND
  P2_6  = GND
  P2_7  = GND
  P2_8  = GND
  P3_1  = GND
  P3_2  = GND
  P3_3  = GND
  P3_4  = GND
  P3_5  = GND
  P3_6  = GND
  P3_7  = GND
  P3_8  = GND
  P4_1  = P12V_PSU
  P4_2  = P12V_PSU
  P4_3  = P12V_PSU
  P4_4  = P12V_PSU
  P4_5  = P12V_PSU
  P4_6  = P12V_PSU
  P4_7  = P12V_PSU
  P4_8  = P12V_PSU
  P5_1  = P12V_PSU
  P5_2  = P12V_PSU
  P5_3  = P12V_PSU
  P5_4  = P12V_PSU
  P5_5  = P12V_PSU
  P5_6  = P12V_PSU
  P5_7  = P12V_PSU
  P5_8  = P12V_PSU
  P6_1  = P12V_PSU
  P6_2  = P12V_PSU
  P6_3  = P12V_PSU
  P6_4  = P12V_PSU
  P6_5  = P12V_PSU
  P6_6  = P12V_PSU
  P6_7  = P12V_PSU
  P6_8  = P12V_PSU

(kicad_pcb
	(version 20260206)
	(generator "pcbnew")
	(generator_version "10.0")
	(general
		(thickness 1.6)
		(legacy_teardrops no)
	)
	(paper "A4")
	(title_block
		(title "03242023_DA0F0TMBIJ0_F0T_Motherboard_J_brd_V01_OCP.brd")
		(comment 1 "Grand Teton / footprint 2359 of 6105 (J45), pads 36-62 of 62")
	)
	(layers
		(0 "F.Cu" signal "TOP")
		(4 "In1.Cu" signal "GND")
		(6 "In2.Cu" signal "IN1")
		(8 "In3.Cu" signal "GND1")
		(10 "In4.Cu" signal "IN2")
		(12 "In5.Cu" signal "GND2")
		(14 "In6.Cu" signal "IN3")
		(16 "In7.Cu" signal "GND3")
		(18 "In8.Cu" signal "VCC")
		(20 "In9.Cu" signal "VCC1")
		(22 "In10.Cu" signal "GND4")
		(24 "In11.Cu" signal "IN4")
		(26 "In12.Cu" signal "GND5")
		(28 "In13.Cu" signal "IN5")
		(30 "In14.Cu" signal "GND6")
		(32 "In15.Cu" signal "IN6")
		(34 "In16.Cu" signal "GND7")
		(2 "B.Cu" signal "BOTTOM")
		(9 "F.Adhes" user "F.Adhesive")
		(11 "B.Adhes" user "B.Adhesive")
		(13 "F.Paste" user "Package Geometry/Pastemask Top")
		(15 "B.Paste" user "Package Geometry/Pastemask Bottom")
		(5 "F.SilkS" user "Ref Des/Silkscreen Top")
		(7 "B.SilkS" user "Ref Des/Silkscreen Bottom")
		(1 "F.Mask" user "Board Geometry/Soldermask Top")
		(3 "B.Mask" user "Board Geometry/Soldermask Bottom")
		(17 "Dwgs.User" user "User.Drawings")
		(19 "Cmts.User" user "User.Comments")
		(21 "Eco1.User" user "User.Eco1")
		(23 "Eco2.User" user "User.Eco2")
		(25 "Edge.Cuts" user "Board Geometry/Outline")
		(27 "Margin" user)
		(31 "F.CrtYd" user "Package Geometry/Place Bound Top")
		(29 "B.CrtYd" user "Package Geometry/Place Bound Bottom")
		(35 "F.Fab" user "Ref Des/Assembly Top")
		(33 "B.Fab" user "Ref Des/Assembly Bottom")
	)
	(footprint ""
		(layer "F.Cu")
		(at 238.45012 -435.58206 -90)
		(property "Reference" "J45"
			(at 7.573772 -37.93236 0)
			(unlocked yes)
			(layer "F.SilkS")
			(effects
				(font
					(size 0.7874 0.5842)
					(thickness 0.1524)
				)
				(justify left)
			)
		)
		(property "Value" ""
			(at 0 0 270)
			(layer "F.Fab")
			(effects
				(font
					(size 1.27 1.27)
				)
			)
		)
		(duplicate_pad_numbers_are_jumpers no)
		(pad "P3_6" thru_hole circle
			(at 2.54 -5.08 270)
			(size 1.669796 1.669796)
			(drill 1.01981)
			(layers "*.Cu" "*.Mask")
			(remove_unused_layers no)
			(net "GND")
			(clearance -0.070866)
		)
		(pad "P3_7" thru_hole circle
			(at 5.08 -5.08 270)
			(size 1.669796 1.669796)
			(drill 1.01981)
			(layers "*.Cu" "*.Mask")
			(remove_unused_layers no)
			(net "GND")
			(clearance -0.070866)
		)
		(pad "P3_8" thru_hole circle
			(at 7.62 -5.08 270)
			(size 1.669796 1.669796)
			(drill 1.01981)
			(layers "*.Cu" "*.Mask")
			(remove_unused_layers no)
			(net "GND")
			(clearance -0.070866)
		)
		(pad "P4_1" thru_hole circle
			(at 0 10.16 270)
			(size 1.669796 1.669796)
			(drill 1.01981)
			(layers "*.Cu" "*.Mask")
			(remove_unused_layers no)
			(net "P12V_PSU")
			(clearance -0.070866)
		)
		(pad "P4_2" thru_hole circle
			(at 2.54 10.16 270)
			(size 1.669796 1.669796)
			(drill 1.01981)
			(layers "*.Cu" "*.Mask")
			(remove_unused_layers no)
			(net "P12V_PSU")
			(clearance -0.070866)
		)
		(pad "P4_3" thru_hole circle
			(at 5.08 10.16 270)
			(size 1.669796 1.669796)
			(drill 1.01981)
			(layers "*.Cu" "*.Mask")
			(remove_unused_layers no)
			(net "P12V_PSU")
			(clearance -0.070866)
		)
		(pad "P4_4" thru_hole circle
			(at 7.62 10.16 270)
			(size 1.669796 1.669796)
			(drill 1.01981)
			(layers "*.Cu" "*.Mask")
			(remove_unused_layers no)
			(net "P12V_PSU")
			(clearance -0.070866)
		)
		(pad "P4_5" thru_hole circle
			(at 0 12.7 270)
			(size 1.669796 1.669796)
			(drill 1.01981)
			(layers "*.Cu" "*.Mask")
			(remove_unused_layers no)
			(net "P12V_PSU")
			(clearance -0.070866)
		)
		(pad "P4_6" thru_hole circle
			(at 2.54 12.7 270)
			(size 1.669796 1.669796)
			(drill 1.01981)
			(layers "*.Cu" "*.Mask")
			(remove_unused_layers no)
			(net "P12V_PSU")
			(clearance -0.070866)
		)
		(pad "P4_7" thru_hole circle
			(at 5.08 12.7 270)
			(size 1.669796 1.669796)
			(drill 1.01981)
			(layers "*.Cu" "*.Mask")
			(remove_unused_layers no)
			(net "P12V_PSU")
			(clearance -0.070866)
		)
		(pad "P4_8" thru_hole circle
			(at 7.62 12.7 270)
			(size 1.669796 1.669796)
			(drill 1.01981)
			(layers "*.Cu" "*.Mask")
			(remove_unused_layers no)
			(net "P12V_PSU")
			(clearance -0.070866)
		)
		(pad "P5_1" thru_hole circle
			(at 0 19.05 270)
			(size 1.669796 1.669796)
			(drill 1.01981)
			(layers "*.Cu" "*.Mask")
			(remove_unused_layers no)
			(net "P12V_PSU")
			(clearance -0.070866)
		)
		(pad "P5_2" thru_hole circle
			(at 2.54 19.05 270)
			(size 1.669796 1.669796)
			(drill 1.01981)
			(layers "*.Cu" "*.Mask")
			(remove_unused_layers no)
			(net "P12V_PSU")
			(clearance -0.070866)
		)
		(pad "P5_3" thru_hole circle
			(at 5.08 19.05 270)
			(size 1.669796 1.669796)
			(drill 1.01981)
			(layers "*.Cu" "*.Mask")
			(remove_unused_layers no)
			(net "P12V_PSU")
			(clearance -0.070866)
		)
		(pad "P5_4" thru_hole circle
			(at 7.62 19.05 270)
			(size 1.669796 1.669796)
			(drill 1.01981)
			(layers "*.Cu" "*.Mask")
			(remove_unused_layers no)
			(net "P12V_PSU")
			(clearance -0.070866)
		)
		(pad "P5_5" thru_hole circle
			(at 0 21.59 270)
			(size 1.669796 1.669796)
			(drill 1.01981)
			(layers "*.Cu" "*.Mask")
			(remove_unused_layers no)
			(net "P12V_PSU")
			(clearance -0.070866)
		)
		(pad "P5_6" thru_hole circle
			(at 2.54 21.59 270)
			(size 1.669796 1.669796)
			(drill 1.01981)
			(layers "*.Cu" "*.Mask")
			(remove_unused_layers no)
			(net "P12V_PSU")
			(clearance -0.070866)
		)
		(pad "P5_7" thru_hole circle
			(at 5.08 21.59 270)
			(size 1.669796 1.669796)
			(drill 1.01981)
			(layers "*.Cu" "*.Mask")
			(remove_unused_layers no)
			(net "P12V_PSU")
			(clearance -0.070866)
		)
		(pad "P5_8" thru_hole circle
			(at 7.62 21.59 270)
			(size 1.669796 1.669796)
			(drill 1.01981)
			(layers "*.Cu" "*.Mask")
			(remove_unused_layers no)
			(net "P12V_PSU")
			(clearance -0.070866)
		)
		(pad "P6_1" thru_hole circle
			(at 0 27.94 270)
			(size 1.669796 1.669796)
			(drill 1.01981)
			(layers "*.Cu" "*.Mask")
			(remove_unused_layers no)
			(net "P12V_PSU")
			(clearance -0.070866)
		)
		(pad "P6_2" thru_hole circle
			(at 2.54 27.94 270)
			(size 1.669796 1.669796)
			(drill 1.01981)
			(layers "*.Cu" "*.Mask")
			(remove_unused_layers no)
			(net "P12V_PSU")
			(clearance -0.070866)
		)
		(pad "P6_3" thru_hole circle
			(at 5.08 27.94 270)
			(size 1.669796 1.669796)
			(drill 1.01981)
			(layers "*.Cu" "*.Mask")
			(remove_unused_layers no)
			(net "P12V_PSU")
			(clearance -0.070866)
		)
		(pad "P6_4" thru_hole circle
			(at 7.62 27.94 270)
			(size 1.669796 1.669796)
			(drill 1.01981)
			(layers "*.Cu" "*.Mask")
			(remove_unused_layers no)
			(net "P12V_PSU")
			(clearance -0.070866)
		)
		(pad "P6_5" thru_hole circle
			(at 0 30.48 270)
			(size 1.669796 1.669796)
			(drill 1.01981)
			(layers "*.Cu" "*.Mask")
			(remove_unused_layers no)
			(net "P12V_PSU")
			(clearance -0.070866)
		)
		(pad "P6_6" thru_hole circle
			(at 2.54 30.48 270)
			(size 1.669796 1.669796)
			(drill 1.01981)
			(layers "*.Cu" "*.Mask")
			(remove_unused_layers no)
			(net "P12V_PSU")
			(clearance -0.070866)
		)
		(pad "P6_7" thru_hole circle
			(at 5.08 30.48 270)
			(size 1.669796 1.669796)
			(drill 1.01981)
			(layers "*.Cu" "*.Mask")
			(remove_unused_layers no)
			(net "P12V_PSU")
			(clearance -0.070866)
		)
		(pad "P6_8" thru_hole circle
			(at 7.62 30.48 270)
			(size 1.669796 1.669796)
			(drill 1.01981)
			(layers "*.Cu" "*.Mask")
			(remove_unused_layers no)
			(net "P12V_PSU")
			(clearance -0.070866)
		)
	)
)
